# BASEBOARD_FAB2 (Tioga Pass) — schematic netlist excerpt (pin names and nets, part order shuffled) for the footprints in the layout excerpt that follows; sources: Cadence DE-HDL packaged netlist, KiCad conversion of Wiwynn_Tioga_Pass_MB.brd

R4A2  RES  0.0 5% CHIP  pkg 0402  page 222 : A = PWRGD_PVDDQ_DEF_R ; B = FM_PVTT_DEF_EN_R
C4A2  CAP  1000PF 50V 10% EMPTY  pkg 0402LF  page 222 : A = FM_PVTT_DEF_EN_R ; B = GND
C9W10  CAP  1000PF 50V 10% X7R  pkg 0402LF  page 239 : A = PWRGD_P2V5_BMC_STBY_R ; B = GND

(kicad_pcb
	(version 20260206)
	(generator "pcbnew")
	(generator_version "10.0")
	(general
		(thickness 1.6)
		(legacy_teardrops no)
	)
	(paper "A4")
	(title_block
		(title "Wiwynn_Tioga_Pass_MB.brd")
		(comment 1 "Tioga Pass / footprints 2183-2185 of 4770")
	)
	(layers
		(0 "F.Cu" signal "TOP")
		(4 "In1.Cu" signal "L2GND")
		(6 "In2.Cu" signal "L3")
		(8 "In3.Cu" signal "L4GND")
		(10 "In4.Cu" signal "L5")
		(12 "In5.Cu" signal "L6GND")
		(14 "In6.Cu" signal "L7VCC")
		(16 "In7.Cu" signal "L8VCC")
		(18 "In8.Cu" signal "L9GND")
		(20 "In9.Cu" signal "L10")
		(22 "In10.Cu" signal "L11GND")
		(24 "In11.Cu" signal "L12")
		(26 "In12.Cu" signal "L13GND")
		(2 "B.Cu" signal "BOTTOM")
		(9 "F.Adhes" user "F.Adhesive")
		(11 "B.Adhes" user "B.Adhesive")
		(13 "F.Paste" user "Package Geometry/Pastemask Top")
		(15 "B.Paste" user "Package Geometry/Pastemask Bottom")
		(5 "F.SilkS" user "Ref Des/Silkscreen Top")
		(7 "B.SilkS" user "Ref Des/Silkscreen Bottom")
		(1 "F.Mask" user "Board Geometry/Soldermask Top")
		(3 "B.Mask" user "Board Geometry/Soldermask Bottom")
		(17 "Dwgs.User" user "User.Drawings")
		(19 "Cmts.User" user "User.Comments")
		(21 "Eco1.User" user "User.Eco1")
		(23 "Eco2.User" user "User.Eco2")
		(25 "Edge.Cuts" user "Board Geometry/Outline")
		(27 "Margin" user)
		(31 "F.CrtYd" user "Package Geometry/Place Bound Top")
		(29 "B.CrtYd" user "Package Geometry/Place Bound Bottom")
		(35 "F.Fab" user "Ref Des/Assembly Top")
		(33 "B.Fab" user "Ref Des/Assembly Bottom")
	)
	(footprint ""
		(layer "F.Cu")
		(at 185.4454 -153.416)
		(property "Reference" "R4A2"
			(at 0 0 0)
			(layer "F.SilkS")
			(hide yes)
			(effects
				(font
					(size 1.27 1.27)
				)
			)
		)
		(property "Value" ""
			(at 0 0 0)
			(layer "F.Fab")
			(effects
				(font
					(size 1.27 1.27)
				)
			)
		)
		(duplicate_pad_numbers_are_jumpers no)
		(fp_poly
			(pts
				(xy -0.2794 -0.1016) (xy 0.2794 -0.1016) (xy 0.2794 0.9906) (xy -0.2794 0.9906)
			)
			(stroke
				(width 0)
				(type default)
			)
			(fill no)
			(layer "F.CrtYd")
		)
		(fp_line
			(start -0.2794 -0.1016)
			(end -0.2794 0.9906)
			(stroke
				(width 0.1)
				(type default)
			)
			(layer "F.Fab")
		)
		(fp_line
			(start -0.2794 0.9906)
			(end 0.2794 0.9906)
			(stroke
				(width 0.1)
				(type default)
			)
			(layer "F.Fab")
		)
		(fp_line
			(start 0.2794 -0.1016)
			(end -0.2794 -0.1016)
			(stroke
				(width 0.1)
				(type default)
			)
			(layer "F.Fab")
		)
		(fp_line
			(start 0.2794 0.9906)
			(end 0.2794 -0.1016)
			(stroke
				(width 0.1)
				(type default)
			)
			(layer "F.Fab")
		)
		(pad "1" smd rect
			(at 0 0)
			(size 0.508 0.508)
			(layers "F.Cu" "F.Mask" "F.Paste")
			(net "PWRGD_PVDDQ_DEF_R")
		)
		(pad "2" smd rect
			(at 0 0.889)
			(size 0.508 0.508)
			(layers "F.Cu" "F.Mask" "F.Paste")
			(net "FM_PVTT_DEF_EN_R")
		)
		(zone
			(layer "F.Cu")
			(hatch none 0.5)
			(connect_pads
				(clearance 0)
			)
			(min_thickness 0.25)
			(keepout
				(tracks allowed)
				(vias not_allowed)
				(pads allowed)
				(copperpour not_allowed)
				(footprints allowed)
			)
			(placement
				(enabled no)
				(sheetname "")
			)
			(fill
				(thermal_gap 0.5)
				(thermal_bridge_width 0.5)
				(island_removal_mode 0)
			)
			(polygon
				(pts
					(xy 185.1914 -153.162) (xy 185.6994 -153.162) (xy 185.6994 -152.781) (xy 185.1914 -152.781)
				)
			)
		)
		(zone
			(layer "F.Cu")
			(hatch none 0.5)
			(connect_pads
				(clearance 0)
			)
			(min_thickness 0.25)
			(keepout
				(tracks not_allowed)
				(vias allowed)
				(pads allowed)
				(copperpour not_allowed)
				(footprints allowed)
			)
			(placement
				(enabled no)
				(sheetname "")
			)
			(fill
				(thermal_gap 0.5)
				(thermal_bridge_width 0.5)
				(island_removal_mode 0)
			)
			(polygon
				(pts
					(xy 185.1914 -152.781) (xy 185.6994 -152.781) (xy 185.6994 -153.162) (xy 185.1914 -153.162)
				)
			)
		)
	)
	(footprint ""
		(layer "F.Cu")
		(at 448.437 -20.2565)
		(property "Reference" "C9W10"
			(at -0.8382 -0.67818 0)
			(unlocked yes)
			(layer "F.SilkS")
			(effects
				(font
					(size 0.4064 0.254)
					(thickness 0.1524)
				)
				(justify left)
			)
		)
		(property "Value" ""
			(at 0 0 0)
			(layer "F.Fab")
			(effects
				(font
					(size 1.27 1.27)
				)
			)
		)
		(duplicate_pad_numbers_are_jumpers no)
		(fp_poly
			(pts
				(xy 0.3048 -0.1016) (xy 0.3048 0.9906) (xy -0.3048 0.9906) (xy -0.3048 -0.1016)
			)
			(stroke
				(width 0)
				(type default)
			)
			(fill no)
			(layer "F.CrtYd")
		)
		(fp_line
			(start -0.3048 -0.1016)
			(end -0.3048 0.9906)
			(stroke
				(width 0.1)
				(type default)
			)
			(layer "F.Fab")
		)
		(fp_line
			(start -0.3048 0.9906)
			(end 0.3048 0.9906)
			(stroke
				(width 0.1)
				(type default)
			)
			(layer "F.Fab")
		)
		(fp_line
			(start 0.3048 -0.1016)
			(end -0.3048 -0.1016)
			(stroke
				(width 0.1)
				(type default)
			)
			(layer "F.Fab")
		)
		(fp_line
			(start 0.3048 0.9906)
			(end 0.3048 -0.1016)
			(stroke
				(width 0.1)
				(type default)
			)
			(layer "F.Fab")
		)
		(pad "1" smd rect
			(at 0 0)
			(size 0.508 0.508)
			(layers "F.Cu" "F.Mask" "F.Paste")
			(net "PWRGD_P2V5_BMC_STBY_R")
		)
		(pad "2" smd rect
			(at 0 0.889)
			(size 0.508 0.508)
			(layers "F.Cu" "F.Mask" "F.Paste")
			(net "GND")
		)
		(zone
			(layer "F.Cu")
			(hatch none 0.5)
			(connect_pads
				(clearance 0)
			)
			(min_thickness 0.25)
			(keepout
				(tracks allowed)
				(vias not_allowed)
				(pads allowed)
				(copperpour not_allowed)
				(footprints allowed)
			)
			(placement
				(enabled no)
				(sheetname "")
			)
			(fill
				(thermal_gap 0.5)
				(thermal_bridge_width 0.5)
				(island_removal_mode 0)
			)
			(polygon
				(pts
					(xy 448.183 -20.0025) (xy 448.691 -20.0025) (xy 448.691 -19.6215) (xy 448.183 -19.6215)
				)
			)
		)
		(zone
			(layer "F.Cu")
			(hatch none 0.5)
			(connect_pads
				(clearance 0)
			)
			(min_thickness 0.25)
			(keepout
				(tracks not_allowed)
				(vias allowed)
				(pads allowed)
				(copperpour not_allowed)
				(footprints allowed)
			)
			(placement
				(enabled no)
				(sheetname "")
			)
			(fill
				(thermal_gap 0.5)
				(thermal_bridge_width 0.5)
				(island_removal_mode 0)
			)
			(polygon
				(pts
					(xy 448.183 -19.6215) (xy 448.691 -19.6215) (xy 448.691 -20.0025) (xy 448.183 -20.0025)
				)
			)
		)
	)
	(footprint ""
		(layer "F.Cu")
		(at 184.6072 -152.527 180)
		(property "Reference" "C4A2"
			(at 0 0 180)
			(layer "F.SilkS")
			(hide yes)
			(effects
				(font
					(size 1.27 1.27)
				)
			)
		)
		(property "Value" ""
			(at 0 0 180)
			(layer "F.Fab")
			(effects
				(font
					(size 1.27 1.27)
				)
			)
		)
		(duplicate_pad_numbers_are_jumpers no)
		(fp_rect
			(start -0.3048 0.9906)
			(end 0.3048 -0.1016)
			(stroke
				(width 0)
				(type default)
			)
			(fill no)
			(layer "F.CrtYd")
		)
		(fp_line
			(start 0.3048 0.9906)
			(end 0.3048 -0.1016)
			(stroke
				(width 0.1)
				(type default)
			)
			(layer "F.Fab")
		)
		(fp_line
			(start 0.3048 -0.1016)
			(end -0.3048 -0.1016)
			(stroke
				(width 0.1)
				(type default)
			)
			(layer "F.Fab")
		)
		(fp_line
			(start -0.3048 0.9906)
			(end 0.3048 0.9906)
			(stroke
				(width 0.1)
				(type default)
			)
			(layer "F.Fab")
		)
		(fp_line
			(start -0.3048 -0.1016)
			(end -0.3048 0.9906)
			(stroke
				(width 0.1)
				(type default)
			)
			(layer "F.Fab")
		)
		(pad "1" smd rect
			(at 0 0 180)
			(size 0.508 0.508)
			(layers "F.Cu" "F.Mask" "F.Paste")
			(net "FM_PVTT_DEF_EN_R")
		)
		(pad "2" smd rect
			(at 0 0.889 180)
			(size 0.508 0.508)
			(layers "F.Cu" "F.Mask" "F.Paste")
			(net "GND")
		)
		(zone
			(layer "F.Cu")
			(hatch none 0.5)
			(connect_pads
				(clearance 0)
			)
			(min_thickness 0.25)
			(keepout
				(tracks not_allowed)
				(vias allowed)
				(pads allowed)
				(copperpour not_allowed)
				(footprints allowed)
			)
			(placement
				(enabled no)
				(sheetname "")
			)
			(fill
				(thermal_gap 0.5)
				(thermal_bridge_width 0.5)
				(island_removal_mode 0)
			)
			(polygon
				(pts
					(xy 184.8612 -153.162) (xy 184.3532 -153.162) (xy 184.3532 -152.781) (xy 184.8612 -152.781)
				)
			)
		)
		(zone
			(layer "F.Cu")
			(hatch none 0.5)
			(connect_pads
				(clearance 0)
			)
			(min_thickness 0.25)
			(keepout
				(tracks allowed)
				(vias not_allowed)
				(pads allowed)
				(copperpour not_allowed)
				(footprints allowed)
			)
			(placement
				(enabled no)
				(sheetname "")
			)
			(fill
				(thermal_gap 0.5)
				(thermal_bridge_width 0.5)
				(island_removal_mode 0)
			)
			(polygon
				(pts
					(xy 184.8612 -153.162) (xy 184.3532 -153.162) (xy 184.3532 -152.781) (xy 184.8612 -152.781)
				)
			)
		)
	)
)
